(kicad_pcb
	(version 20260206)
	(generator "pcbnew")
	(generator_version "10.0")
	(general
		(thickness 1.6)
		(legacy_teardrops no)
	)
	(paper "A4")
	(title_block
		(title "01162023_DA0F0TEBIF0_F0T_Expander_BD_F_brd_V02_OCP.brd")
		(comment 1 "Grand Teton / footprints 8613-8621 of 9728")
	)
	(layers
		(0 "F.Cu" signal "TOP")
		(4 "In1.Cu" signal "GND")
		(6 "In2.Cu" signal "VCC")
		(8 "In3.Cu" signal "VCC1")
		(10 "In4.Cu" signal "GND1")
		(12 "In5.Cu" signal "IN1")
		(14 "In6.Cu" signal "GND2")
		(16 "In7.Cu" signal "IN2")
		(18 "In8.Cu" signal "GND3")
		(20 "In9.Cu" signal "IN3")
		(22 "In10.Cu" signal "GND4")
		(24 "In11.Cu" signal "IN4")
		(26 "In12.Cu" signal "GND5")
		(28 "In13.Cu" signal "IN5")
		(30 "In14.Cu" signal "GND6")
		(32 "In15.Cu" signal "IN6")
		(34 "In16.Cu" signal "GND7")
		(2 "B.Cu" signal "BOTTOM")
		(9 "F.Adhes" user "F.Adhesive")
		(11 "B.Adhes" user "B.Adhesive")
		(13 "F.Paste" user "Package Geometry/Pastemask Top")
		(15 "B.Paste" user "Package Geometry/Pastemask Bottom")
		(5 "F.SilkS" user "Ref Des/Silkscreen Top")
		(7 "B.SilkS" user "Ref Des/Silkscreen Bottom")
		(1 "F.Mask" user "Board Geometry/Soldermask Top")
		(3 "B.Mask" user "Board Geometry/Soldermask Bottom")
		(17 "Dwgs.User" user "User.Drawings")
		(19 "Cmts.User" user "User.Comments")
		(21 "Eco1.User" user "User.Eco1")
		(23 "Eco2.User" user "User.Eco2")
		(25 "Edge.Cuts" user "Board Geometry/Outline")
		(27 "Margin" user)
		(31 "F.CrtYd" user "Package Geometry/Place Bound Top")
		(29 "B.CrtYd" user "Package Geometry/Place Bound Bottom")
		(35 "F.Fab" user "Ref Des/Assembly Top")
		(33 "B.Fab" user "Ref Des/Assembly Bottom")
	)
	(footprint ""
		(layer "B.Cu")
		(at 366.492536 -328.422)
		(property "Reference" "PJ24"
			(at 0 0 0)
			(layer "B.SilkS")
			(hide yes)
			(effects
				(font
					(size 1.27 1.27)
				)
				(justify mirror)
			)
		)
		(property "Value" ""
			(at 0 0 0)
			(layer "B.Fab")
			(effects
				(font
					(size 1.27 1.27)
				)
				(justify mirror)
			)
		)
		(duplicate_pad_numbers_are_jumpers no)
		(pad "1" smd circle
			(at 0.40005 0 90)
			(size 0 0)
			(layers "B.Cu" "B.Mask" "B.Paste")
			(net "VSENSE_P0V8_PEX3_SKT_VSEN")
		)
		(pad "2" smd rect
			(at -0.40005 0)
			(size 0.4572 0.508)
			(layers "B.Cu" "B.Mask" "B.Paste")
			(net "SH_P0V8_PEX3_VSEN3_L")
		)
		(zone
			(layer "B.Cu")
			(hatch none 0.5)
			(connect_pads
				(clearance 0)
			)
			(min_thickness 0.25)
			(keepout
				(tracks allowed)
				(vias not_allowed)
				(pads allowed)
				(copperpour not_allowed)
				(footprints allowed)
			)
			(placement
				(enabled no)
				(sheetname "")
			)
			(fill
				(thermal_gap 0.5)
				(thermal_bridge_width 0.5)
				(island_removal_mode 0)
			)
			(polygon
				(pts
					(xy 365.806736 -328.1172) (xy 365.806736 -328.7268) (xy 367.178336 -328.7268) (xy 367.178336 -328.1172)
				)
			)
		)
	)
	(footprint ""
		(layer "B.Cu")
		(at 285.245556 -296.37482)
		(property "Reference" "C1618"
			(at 0 0 0)
			(layer "B.SilkS")
			(hide yes)
			(effects
				(font
					(size 1.27 1.27)
				)
				(justify mirror)
			)
		)
		(property "Value" ""
			(at 0 0 0)
			(layer "B.Fab")
			(effects
				(font
					(size 1.27 1.27)
				)
				(justify mirror)
			)
		)
		(duplicate_pad_numbers_are_jumpers no)
		(fp_line
			(start -0.299974 -0.150114)
			(end -0.299974 0.150114)
			(stroke
				(width 0.1)
				(type default)
			)
			(layer "B.Fab")
		)
		(fp_line
			(start -0.299974 0.150114)
			(end 0.299974 0.150114)
			(stroke
				(width 0.1)
				(type default)
			)
			(layer "B.Fab")
		)
		(fp_line
			(start 0.299974 -0.150114)
			(end -0.299974 -0.150114)
			(stroke
				(width 0.1)
				(type default)
			)
			(layer "B.Fab")
		)
		(fp_line
			(start 0.299974 0.150114)
			(end 0.299974 -0.150114)
			(stroke
				(width 0.1)
				(type default)
			)
			(layer "B.Fab")
		)
		(pad "1" smd rect
			(at 0.2667 0 180)
			(size 0.3048 0.381)
			(layers "B.Cu" "B.Mask" "B.Paste")
			(net "P0V8_PEX2")
		)
		(pad "2" smd rect
			(at -0.2667 0 180)
			(size 0.3048 0.381)
			(layers "B.Cu" "B.Mask" "B.Paste")
			(net "GND")
		)
	)
	(footprint ""
		(layer "B.Cu")
		(at 425.841922 -95.989648 180)
		(property "Reference" "R368"
			(at 0 0 0)
			(layer "B.SilkS")
			(hide yes)
			(effects
				(font
					(size 1.27 1.27)
				)
				(justify mirror)
			)
		)
		(property "Value" ""
			(at 0 0 0)
			(layer "B.Fab")
			(effects
				(font
					(size 1.27 1.27)
				)
				(justify mirror)
			)
		)
		(duplicate_pad_numbers_are_jumpers no)
		(fp_line
			(start 0.7874 0.4064)
			(end 0.7874 -0.4064)
			(stroke
				(width 0.1524)
				(type default)
			)
			(layer "B.SilkS")
		)
		(fp_line
			(start 0.7874 -0.4064)
			(end -0.7874 -0.4064)
			(stroke
				(width 0.1524)
				(type default)
			)
			(layer "B.SilkS")
		)
		(fp_line
			(start -0.7874 0.4064)
			(end 0.7874 0.4064)
			(stroke
				(width 0.1524)
				(type default)
			)
			(layer "B.SilkS")
		)
		(fp_line
			(start -0.7874 -0.4064)
			(end -0.7874 0.4064)
			(stroke
				(width 0.1524)
				(type default)
			)
			(layer "B.SilkS")
		)
		(fp_line
			(start 0.67945 0.3048)
			(end 0.67945 -0.305054)
			(stroke
				(width 0.1)
				(type default)
			)
			(layer "B.Fab")
		)
		(fp_line
			(start 0.67945 -0.305054)
			(end 0.12065 -0.305054)
			(stroke
				(width 0.1)
				(type default)
			)
			(layer "B.Fab")
		)
		(fp_line
			(start 0.12065 0.3048)
			(end 0.67945 0.3048)
			(stroke
				(width 0.1)
				(type default)
			)
			(layer "B.Fab")
		)
		(fp_line
			(start 0.12065 0.2794)
			(end 0.12065 0.3048)
			(stroke
				(width 0.1)
				(type default)
			)
			(layer "B.Fab")
		)
		(fp_line
			(start 0.12065 -0.2794)
			(end -0.12065 -0.2794)
			(stroke
				(width 0.1)
				(type default)
			)
			(layer "B.Fab")
		)
		(fp_line
			(start 0.12065 -0.305054)
			(end 0.12065 -0.2794)
			(stroke
				(width 0.1)
				(type default)
			)
			(layer "B.Fab")
		)
		(fp_line
			(start -0.120396 0.3048)
			(end -0.120396 0.2794)
			(stroke
				(width 0.1)
				(type default)
			)
			(layer "B.Fab")
		)
		(fp_line
			(start -0.120396 0.2794)
			(end 0.12065 0.2794)
			(stroke
				(width 0.1)
				(type default)
			)
			(layer "B.Fab")
		)
		(fp_line
			(start -0.12065 -0.2794)
			(end -0.12065 -0.3048)
			(stroke
				(width 0.1)
				(type default)
			)
			(layer "B.Fab")
		)
		(fp_line
			(start -0.12065 -0.3048)
			(end -0.67945 -0.3048)
			(stroke
				(width 0.1)
				(type default)
			)
			(layer "B.Fab")
		)
		(fp_line
			(start -0.67945 0.3048)
			(end -0.120396 0.3048)
			(stroke
				(width 0.1)
				(type default)
			)
			(layer "B.Fab")
		)
		(fp_line
			(start -0.67945 -0.3048)
			(end -0.67945 0.3048)
			(stroke
				(width 0.1)
				(type default)
			)
			(layer "B.Fab")
		)
		(pad "1" smd circle
			(at 0.40005 0)
			(size 0 0)
			(layers "B.Cu" "B.Mask" "B.Paste")
			(net "NIC7_LD_N")
		)
		(pad "2" smd circle
			(at -0.40005 0)
			(size 0 0)
			(layers "B.Cu" "B.Mask" "B.Paste")
			(net "P3V3_NIC7")
		)
	)
	(footprint ""
		(layer "B.Cu")
		(at 421.700198 -110.978696)
		(property "Reference" "C956"
			(at 0 0 0)
			(layer "B.SilkS")
			(hide yes)
			(effects
				(font
					(size 1.27 1.27)
				)
				(justify mirror)
			)
		)
		(property "Value" ""
			(at 0 0 0)
			(layer "B.Fab")
			(effects
				(font
					(size 1.27 1.27)
				)
				(justify mirror)
			)
		)
		(duplicate_pad_numbers_are_jumpers no)
		(fp_line
			(start -0.299974 -0.150114)
			(end -0.299974 0.150114)
			(stroke
				(width 0.1)
				(type default)
			)
			(layer "B.Fab")
		)
		(fp_line
			(start -0.299974 0.150114)
			(end 0.299974 0.150114)
			(stroke
				(width 0.1)
				(type default)
			)
			(layer "B.Fab")
		)
		(fp_line
			(start 0.299974 -0.150114)
			(end -0.299974 -0.150114)
			(stroke
				(width 0.1)
				(type default)
			)
			(layer "B.Fab")
		)
		(fp_line
			(start 0.299974 0.150114)
			(end 0.299974 -0.150114)
			(stroke
				(width 0.1)
				(type default)
			)
			(layer "B.Fab")
		)
		(pad "1" smd rect
			(at 0.2667 0 180)
			(size 0.3048 0.381)
			(layers "B.Cu" "B.Mask" "B.Paste")
			(net "P12V_NIC7")
		)
		(pad "2" smd rect
			(at -0.2667 0 180)
			(size 0.3048 0.381)
			(layers "B.Cu" "B.Mask" "B.Paste")
			(net "GND")
		)
	)
	(footprint ""
		(layer "B.Cu")
		(at 171.949872 -301.599854 -90)
		(property "Reference" "C1484"
			(at 0 0 90)
			(layer "B.SilkS")
			(hide yes)
			(effects
				(font
					(size 1.27 1.27)
				)
				(justify mirror)
			)
		)
		(property "Value" ""
			(at 0 0 90)
			(layer "B.Fab")
			(effects
				(font
					(size 1.27 1.27)
				)
				(justify mirror)
			)
		)
		(duplicate_pad_numbers_are_jumpers no)
		(fp_line
			(start -0.299974 0.150114)
			(end 0.299974 0.150114)
			(stroke
				(width 0.1)
				(type default)
			)
			(layer "B.Fab")
		)
		(fp_line
			(start 0.299974 0.150114)
			(end 0.299974 -0.150114)
			(stroke
				(width 0.1)
				(type default)
			)
			(layer "B.Fab")
		)
		(fp_line
			(start -0.299974 -0.150114)
			(end -0.299974 0.150114)
			(stroke
				(width 0.1)
				(type default)
			)
			(layer "B.Fab")
		)
		(fp_line
			(start 0.299974 -0.150114)
			(end -0.299974 -0.150114)
			(stroke
				(width 0.1)
				(type default)
			)
			(layer "B.Fab")
		)
		(pad "1" smd rect
			(at 0.2667 0 90)
			(size 0.3048 0.381)
			(layers "B.Cu" "B.Mask" "B.Paste")
			(net "P0V8_SERDES_VDDA_PEX1")
		)
		(pad "2" smd rect
			(at -0.2667 0 90)
			(size 0.3048 0.381)
			(layers "B.Cu" "B.Mask" "B.Paste")
			(net "GND")
		)
	)
	(footprint ""
		(layer "B.Cu")
		(at 342.094058 -217.187018 -90)
		(property "Reference" "C2054"
			(at 0 0 90)
			(layer "B.SilkS")
			(hide yes)
			(effects
				(font
					(size 1.27 1.27)
				)
				(justify mirror)
			)
		)
		(property "Value" ""
			(at 0 0 90)
			(layer "B.Fab")
			(effects
				(font
					(size 1.27 1.27)
				)
				(justify mirror)
			)
		)
		(duplicate_pad_numbers_are_jumpers no)
		(fp_line
			(start -0.69215 0.2921)
			(end 0.69215 0.2921)
			(stroke
				(width 0.1524)
				(type default)
			)
			(layer "B.SilkS")
		)
		(fp_line
			(start 0.69215 0.2921)
			(end 0.69215 -0.2921)
			(stroke
				(width 0.1524)
				(type default)
			)
			(layer "B.SilkS")
		)
		(fp_line
			(start -0.69215 -0.2921)
			(end -0.69215 0.2921)
			(stroke
				(width 0.1524)
				(type default)
			)
			(layer "B.SilkS")
		)
		(fp_line
			(start 0.69215 -0.2921)
			(end -0.69215 -0.2921)
			(stroke
				(width 0.1524)
				(type default)
			)
			(layer "B.SilkS")
		)
		(fp_line
			(start -0.51435 0.2794)
			(end 0.51435 0.2794)
			(stroke
				(width 0.1)
				(type default)
			)
			(layer "B.Fab")
		)
		(fp_line
			(start 0.51435 0.2794)
			(end 0.51435 -0.2794)
			(stroke
				(width 0.1)
				(type default)
			)
			(layer "B.Fab")
		)
		(fp_line
			(start -0.51435 -0.2794)
			(end -0.51435 0.2794)
			(stroke
				(width 0.1)
				(type default)
			)
			(layer "B.Fab")
		)
		(fp_line
			(start 0.51435 -0.2794)
			(end -0.51435 -0.2794)
			(stroke
				(width 0.1)
				(type default)
			)
			(layer "B.Fab")
		)
		(pad "1" smd circle
			(at 0.40005 0 90)
			(size 0 0)
			(layers "B.Cu" "B.Mask" "B.Paste")
			(net "P3V3_FPGA_VCCIO2")
		)
		(pad "2" smd circle
			(at -0.40005 0 90)
			(size 0 0)
			(layers "B.Cu" "B.Mask" "B.Paste")
			(net "GND")
		)
		(zone
			(layer "B.Cu")
			(hatch none 0.5)
			(connect_pads
				(clearance 0)
			)
			(min_thickness 0.25)
			(keepout
				(tracks not_allowed)
				(vias allowed)
				(pads allowed)
				(copperpour not_allowed)
				(footprints allowed)
			)
			(placement
				(enabled no)
				(sheetname "")
			)
			(fill
				(thermal_gap 0.5)
				(thermal_bridge_width 0.5)
				(island_removal_mode 0)
			)
			(polygon
				(pts
					(xy 342.006428 -216.996518) (xy 341.948262 -217.087958) (xy 341.948262 -217.287348) (xy 342.006428 -217.377518)
					(xy 342.181688 -217.377518) (xy 342.240108 -217.287348) (xy 342.240108 -217.087958) (xy 342.181942 -216.996518)
				)
			)
		)
	)
	(footprint ""
		(layer "B.Cu")
		(at 49.40808 -303.024794 180)
		(property "Reference" "C3011"
			(at 0 0 0)
			(layer "B.SilkS")
			(hide yes)
			(effects
				(font
					(size 1.27 1.27)
				)
				(justify mirror)
			)
		)
		(property "Value" ""
			(at 0 0 0)
			(layer "B.Fab")
			(effects
				(font
					(size 1.27 1.27)
				)
				(justify mirror)
			)
		)
		(duplicate_pad_numbers_are_jumpers no)
		(fp_line
			(start 0.299974 0.150114)
			(end 0.299974 -0.150114)
			(stroke
				(width 0.1)
				(type default)
			)
			(layer "B.Fab")
		)
		(fp_line
			(start 0.299974 -0.150114)
			(end -0.299974 -0.150114)
			(stroke
				(width 0.1)
				(type default)
			)
			(layer "B.Fab")
		)
		(fp_line
			(start -0.299974 0.150114)
			(end 0.299974 0.150114)
			(stroke
				(width 0.1)
				(type default)
			)
			(layer "B.Fab")
		)
		(fp_line
			(start -0.299974 -0.150114)
			(end -0.299974 0.150114)
			(stroke
				(width 0.1)
				(type default)
			)
			(layer "B.Fab")
		)
		(pad "1" smd rect
			(at 0.2667 0)
			(size 0.3048 0.381)
			(layers "B.Cu" "B.Mask" "B.Paste")
			(net "P1V8_VDDA_PEX0")
		)
		(pad "2" smd rect
			(at -0.2667 0)
			(size 0.3048 0.381)
			(layers "B.Cu" "B.Mask" "B.Paste")
			(net "GND")
		)
	)
	(footprint ""
		(layer "B.Cu")
		(at 293.797228 -108.465366)
		(property "Reference" "R284"
			(at 0 0 0)
			(layer "B.SilkS")
			(hide yes)
			(effects
				(font
					(size 1.27 1.27)
				)
				(justify mirror)
			)
		)
		(property "Value" ""
			(at 0 0 0)
			(layer "B.Fab")
			(effects
				(font
					(size 1.27 1.27)
				)
				(justify mirror)
			)
		)
		(duplicate_pad_numbers_are_jumpers no)
		(fp_line
			(start -0.7874 -0.4064)
			(end -0.7874 0.4064)
			(stroke
				(width 0.1524)
				(type default)
			)
			(layer "B.SilkS")
		)
		(fp_line
			(start -0.7874 0.4064)
			(end 0.7874 0.4064)
			(stroke
				(width 0.1524)
				(type default)
			)
			(layer "B.SilkS")
		)
		(fp_line
			(start 0.7874 -0.4064)
			(end -0.7874 -0.4064)
			(stroke
				(width 0.1524)
				(type default)
			)
			(layer "B.SilkS")
		)
		(fp_line
			(start 0.7874 0.4064)
			(end 0.7874 -0.4064)
			(stroke
				(width 0.1524)
				(type default)
			)
			(layer "B.SilkS")
		)
		(fp_line
			(start -0.67945 -0.3048)
			(end -0.67945 0.3048)
			(stroke
				(width 0.1)
				(type default)
			)
			(layer "B.Fab")
		)
		(fp_line
			(start -0.67945 0.3048)
			(end -0.120396 0.3048)
			(stroke
				(width 0.1)
				(type default)
			)
			(layer "B.Fab")
		)
		(fp_line
			(start -0.12065 -0.3048)
			(end -0.67945 -0.3048)
			(stroke
				(width 0.1)
				(type default)
			)
			(layer "B.Fab")
		)
		(fp_line
			(start -0.12065 -0.2794)
			(end -0.12065 -0.3048)
			(stroke
				(width 0.1)
				(type default)
			)
			(layer "B.Fab")
		)
		(fp_line
			(start -0.120396 0.2794)
			(end 0.12065 0.2794)
			(stroke
				(width 0.1)
				(type default)
			)
			(layer "B.Fab")
		)
		(fp_line
			(start -0.120396 0.3048)
			(end -0.120396 0.2794)
			(stroke
				(width 0.1)
				(type default)
			)
			(layer "B.Fab")
		)
		(fp_line
			(start 0.12065 -0.305054)
			(end 0.12065 -0.2794)
			(stroke
				(width 0.1)
				(type default)
			)
			(layer "B.Fab")
		)
		(fp_line
			(start 0.12065 -0.2794)
			(end -0.12065 -0.2794)
			(stroke
				(width 0.1)
				(type default)
			)
			(layer "B.Fab")
		)
		(fp_line
			(start 0.12065 0.2794)
			(end 0.12065 0.3048)
			(stroke
				(width 0.1)
				(type default)
			)
			(layer "B.Fab")
		)
		(fp_line
			(start 0.12065 0.3048)
			(end 0.67945 0.3048)
			(stroke
				(width 0.1)
				(type default)
			)
			(layer "B.Fab")
		)
		(fp_line
			(start 0.67945 -0.305054)
			(end 0.12065 -0.305054)
			(stroke
				(width 0.1)
				(type default)
			)
			(layer "B.Fab")
		)
		(fp_line
			(start 0.67945 0.3048)
			(end 0.67945 -0.305054)
			(stroke
				(width 0.1)
				(type default)
			)
			(layer "B.Fab")
		)
		(pad "1" smd circle
			(at 0.40005 0 180)
			(size 0 0)
			(layers "B.Cu" "B.Mask" "B.Paste")
			(net "NIC5_BIF0_N")
		)
		(pad "2" smd circle
			(at -0.40005 0 180)
			(size 0 0)
			(layers "B.Cu" "B.Mask" "B.Paste")
			(net "P3V3_AUX")
		)
	)
	(footprint ""
		(layer "B.Cu")
		(at 63.375286 -110.497366 180)
		(property "Reference" "R85"
			(at 0 0 0)
			(layer "B.SilkS")
			(hide yes)
			(effects
				(font
					(size 1.27 1.27)
				)
				(justify mirror)
			)
		)
		(property "Value" ""
			(at 0 0 0)
			(layer "B.Fab")
			(effects
				(font
					(size 1.27 1.27)
				)
				(justify mirror)
			)
		)
		(duplicate_pad_numbers_are_jumpers no)
		(fp_line
			(start 0.7874 0.4064)
			(end 0.7874 -0.4064)
			(stroke
				(width 0.1524)
				(type default)
			)
			(layer "B.SilkS")
		)
		(fp_line
			(start 0.7874 -0.4064)
			(end -0.7874 -0.4064)
			(stroke
				(width 0.1524)
				(type default)
			)
			(layer "B.SilkS")
		)
		(fp_line
			(start -0.7874 0.4064)
			(end 0.7874 0.4064)
			(stroke
				(width 0.1524)
				(type default)
			)
			(layer "B.SilkS")
		)
		(fp_line
			(start -0.7874 -0.4064)
			(end -0.7874 0.4064)
			(stroke
				(width 0.1524)
				(type default)
			)
			(layer "B.SilkS")
		)
		(fp_line
			(start 0.67945 0.3048)
			(end 0.67945 -0.305054)
			(stroke
				(width 0.1)
				(type default)
			)
			(layer "B.Fab")
		)
		(fp_line
			(start 0.67945 -0.305054)
			(end 0.12065 -0.305054)
			(stroke
				(width 0.1)
				(type default)
			)
			(layer "B.Fab")
		)
		(fp_line
			(start 0.12065 0.3048)
			(end 0.67945 0.3048)
			(stroke
				(width 0.1)
				(type default)
			)
			(layer "B.Fab")
		)
		(fp_line
			(start 0.12065 0.2794)
			(end 0.12065 0.3048)
			(stroke
				(width 0.1)
				(type default)
			)
			(layer "B.Fab")
		)
		(fp_line
			(start 0.12065 -0.2794)
			(end -0.12065 -0.2794)
			(stroke
				(width 0.1)
				(type default)
			)
			(layer "B.Fab")
		)
		(fp_line
			(start 0.12065 -0.305054)
			(end 0.12065 -0.2794)
			(stroke
				(width 0.1)
				(type default)
			)
			(layer "B.Fab")
		)
		(fp_line
			(start -0.120396 0.3048)
			(end -0.120396 0.2794)
			(stroke
				(width 0.1)
				(type default)
			)
			(layer "B.Fab")
		)
		(fp_line
			(start -0.120396 0.2794)
			(end 0.12065 0.2794)
			(stroke
				(width 0.1)
				(type default)
			)
			(layer "B.Fab")
		)
		(fp_line
			(start -0.12065 -0.2794)
			(end -0.12065 -0.3048)
			(stroke
				(width 0.1)
				(type default)
			)
			(layer "B.Fab")
		)
		(fp_line
			(start -0.12065 -0.3048)
			(end -0.67945 -0.3048)
			(stroke
				(width 0.1)
				(type default)
			)
			(layer "B.Fab")
		)
		(fp_line
			(start -0.67945 0.3048)
			(end -0.120396 0.3048)
			(stroke
				(width 0.1)
				(type default)
			)
			(layer "B.Fab")
		)
		(fp_line
			(start -0.67945 -0.3048)
			(end -0.67945 0.3048)
			(stroke
				(width 0.1)
				(type default)
			)
			(layer "B.Fab")
		)
		(pad "1" smd circle
			(at 0.40005 0)
			(size 0 0)
			(layers "B.Cu" "B.Mask" "B.Paste")
			(net "NIC1_BIF2_N")
		)
		(pad "2" smd circle
			(at -0.40005 0)
			(size 0 0)
			(layers "B.Cu" "B.Mask" "B.Paste")
			(net "GND")
		)
	)
)
